(kicad_pcb
	(version 20260206)
	(generator "pcbnew")
	(generator_version "10.0")
	(general
		(thickness 1.6)
		(legacy_teardrops no)
	)
	(paper "A4")
	(title_block
		(title "baseboard — 13948-1b.1110WZS1818.brd")
		(comment 1 "Honey Badger (Wiwynn) / footprints 535-540 of 2523")
	)
	(layers
		(0 "F.Cu" signal "TOP")
		(4 "In1.Cu" signal "L2GND")
		(6 "In2.Cu" signal "L3")
		(8 "In3.Cu" signal "L4VCC")
		(10 "In4.Cu" signal "L5VCC")
		(12 "In5.Cu" signal "L6")
		(14 "In6.Cu" signal "L7GND")
		(2 "B.Cu" signal "BOTTOM")
		(9 "F.Adhes" user "F.Adhesive")
		(11 "B.Adhes" user "B.Adhesive")
		(13 "F.Paste" user "Package Geometry/Pastemask Top")
		(15 "B.Paste" user "Package Geometry/Pastemask Bottom")
		(5 "F.SilkS" user "Ref Des/Silkscreen Top")
		(7 "B.SilkS" user "Ref Des/Silkscreen Bottom")
		(1 "F.Mask" user "Board Geometry/Soldermask Top")
		(3 "B.Mask" user "Board Geometry/Soldermask Bottom")
		(17 "Dwgs.User" user "User.Drawings")
		(19 "Cmts.User" user "User.Comments")
		(21 "Eco1.User" user "User.Eco1")
		(23 "Eco2.User" user "User.Eco2")
		(25 "Edge.Cuts" user "Board Geometry/Outline")
		(27 "Margin" user)
		(31 "F.CrtYd" user "Package Geometry/Place Bound Top")
		(29 "B.CrtYd" user "Package Geometry/Place Bound Bottom")
		(35 "F.Fab" user "Ref Des/Assembly Top")
		(33 "B.Fab" user "Ref Des/Assembly Bottom")
	)
	(footprint ""
		(layer "F.Cu")
		(at 52.08397 -134.62 90)
		(property "Reference" "U39"
			(at 0 0 90)
			(layer "F.SilkS")
			(hide yes)
			(effects
				(font
					(size 1.27 1.27)
				)
			)
		)
		(property "Value" "SN74LVC1G08DCKR-GP"
			(at -2.3368 -8.6868 90)
			(unlocked yes)
			(layer "F.Fab")
			(hide yes)
			(effects
				(font
					(size 1.016 1.016)
					(thickness 0.1524)
				)
			)
		)
		(property "Device Type" "SC70-5H44"
			(at -2.3114 -10.414 90)
			(unlocked yes)
			(layer "F.Fab")
			(hide yes)
			(effects
				(font
					(size 1.016 1.016)
					(thickness 0.1524)
				)
			)
		)
		(duplicate_pad_numbers_are_jumpers no)
		(fp_line
			(start 1.3843 -1.8034)
			(end 1.3843 -1.1176)
			(stroke
				(width 0.3302)
				(type default)
			)
			(layer "F.SilkS")
		)
		(fp_line
			(start 0.6604 -1.8034)
			(end 1.3843 -1.8034)
			(stroke
				(width 0.3302)
				(type default)
			)
			(layer "F.SilkS")
		)
		(fp_line
			(start 1.27 -1.7018)
			(end 1.27 1.7018)
			(stroke
				(width 0.1524)
				(type default)
			)
			(layer "F.SilkS")
		)
		(fp_line
			(start -1.27 -1.7018)
			(end 1.27 -1.7018)
			(stroke
				(width 0.1524)
				(type default)
			)
			(layer "F.SilkS")
		)
		(fp_line
			(start 1.27 1.7018)
			(end -1.27 1.7018)
			(stroke
				(width 0.1524)
				(type default)
			)
			(layer "F.SilkS")
		)
		(fp_line
			(start -1.27 1.7018)
			(end -1.27 -1.7018)
			(stroke
				(width 0.1524)
				(type default)
			)
			(layer "F.SilkS")
		)
		(fp_rect
			(start -1.524 1.9558)
			(end 1.524 -1.9558)
			(stroke
				(width 0)
				(type default)
			)
			(fill no)
			(layer "F.CrtYd")
		)
		(fp_poly
			(pts
				(xy -1.524 -1.9558) (xy 1.524 -1.9558) (xy 1.524 1.9558) (xy -1.524 1.9558)
			)
			(stroke
				(width 0)
				(type default)
			)
			(fill no)
			(layer "F.Fab")
		)
		(pad "1" smd rect
			(at 0.65024 -0.8255 90)
			(size 0.4064 1.2192)
			(layers "F.Cu" "F.Mask" "F.Paste")
			(net "RESET_AND_N")
		)
		(pad "2" smd rect
			(at 0 -0.8255 90)
			(size 0.4064 1.2192)
			(layers "F.Cu" "F.Mask" "F.Paste")
			(net "BMC_EXP_RESET_N")
		)
		(pad "3" smd rect
			(at -0.65024 -0.8255 90)
			(size 0.4064 1.2192)
			(layers "F.Cu" "F.Mask" "F.Paste")
			(net "GND")
		)
		(pad "4" smd rect
			(at -0.65024 0.8255 90)
			(size 0.4064 1.2192)
			(layers "F.Cu" "F.Mask" "F.Paste")
			(net "EXP_RST_1")
		)
		(pad "5" smd rect
			(at 0.65024 0.8255 90)
			(size 0.4064 1.2192)
			(layers "F.Cu" "F.Mask" "F.Paste")
			(net "P1V8_E")
		)
	)
	(footprint ""
		(layer "F.Cu")
		(at 319.660016 -88.650064 -90)
		(property "Reference" "BAT1"
			(at 0 0 270)
			(layer "F.SilkS")
			(hide yes)
			(effects
				(font
					(size 1.27 1.27)
				)
			)
		)
		(property "Value" "BAT-AAA-BAT-043-K01-GP"
			(at -10.2616 -6.7056 270)
			(unlocked yes)
			(layer "F.Fab")
			(hide yes)
			(effects
				(font
					(size 1.016 1.016)
					(thickness 0.1524)
				)
			)
		)
		(property "Device Type" "AAA-BAT-043-K01"
			(at -10.2616 -8.2296 270)
			(unlocked yes)
			(layer "F.Fab")
			(hide yes)
			(effects
				(font
					(size 1.016 1.016)
					(thickness 0.1524)
				)
			)
		)
		(duplicate_pad_numbers_are_jumpers no)
		(fp_line
			(start -5.38099 2.0574)
			(end -4.61899 2.0574)
			(stroke
				(width 0.1524)
				(type default)
			)
			(layer "F.SilkS")
		)
		(fp_line
			(start 4.61899 2.0574)
			(end 5.38099 2.0574)
			(stroke
				(width 0.1524)
				(type default)
			)
			(layer "F.SilkS")
		)
		(fp_line
			(start -4.99999 1.6764)
			(end -4.99999 2.4384)
			(stroke
				(width 0.1524)
				(type default)
			)
			(layer "F.SilkS")
		)
		(fp_line
			(start 4.99999 1.6764)
			(end 4.99999 2.4384)
			(stroke
				(width 0.1524)
				(type default)
			)
			(layer "F.SilkS")
		)
		(fp_line
			(start 10.7569 1.4732)
			(end 12.0269 1.4732)
			(stroke
				(width 0.4064)
				(type default)
			)
			(layer "F.SilkS")
		)
		(fp_line
			(start 12.0269 1.4732)
			(end 12.0269 0.2032)
			(stroke
				(width 0.4064)
				(type default)
			)
			(layer "F.SilkS")
		)
		(fp_line
			(start -11.8999 1.3462)
			(end -11.8999 -4.953)
			(stroke
				(width 0.1524)
				(type default)
			)
			(layer "F.SilkS")
		)
		(fp_line
			(start 11.8999 1.3462)
			(end -11.8999 1.3462)
			(stroke
				(width 0.1524)
				(type default)
			)
			(layer "F.SilkS")
		)
		(fp_line
			(start -11.8999 -4.953)
			(end 11.8999 -4.953)
			(stroke
				(width 0.1524)
				(type default)
			)
			(layer "F.SilkS")
		)
		(fp_line
			(start 11.8999 -4.953)
			(end 11.8999 1.3462)
			(stroke
				(width 0.1524)
				(type default)
			)
			(layer "F.SilkS")
		)
		(fp_line
			(start -0.381 -5.301234)
			(end 0.381 -5.301234)
			(stroke
				(width 0.1524)
				(type default)
			)
			(layer "F.SilkS")
		)
		(fp_circle
			(center -4.99999 0)
			(end -4.99999 -1.0922)
			(stroke
				(width 0.3048)
				(type default)
			)
			(fill no)
			(layer "F.SilkS")
		)
		(fp_circle
			(center 4.99999 0)
			(end 4.99999 -1.0922)
			(stroke
				(width 0.3048)
				(type default)
			)
			(fill no)
			(layer "F.SilkS")
		)
		(fp_circle
			(center 0 -3.599942)
			(end 0 -4.692142)
			(stroke
				(width 0.3048)
				(type default)
			)
			(fill no)
			(layer "F.SilkS")
		)
		(fp_rect
			(start -11.6459 1.0922)
			(end 11.6459 -4.699)
			(stroke
				(width 0)
				(type default)
			)
			(fill no)
			(layer "F.CrtYd")
		)
		(fp_poly
			(pts
				(xy -0.1016 -5.207) (xy -0.1016 -4.699) (xy 11.6459 -4.699) (xy 11.6459 1.0922) (xy -11.6459 1.0922)
				(xy -11.6459 -4.699) (xy -0.1143 -4.699) (xy -0.1143 -5.207) (xy -12.1539 -5.207) (xy -12.1539 1.6002)
				(xy 12.1539 1.6002) (xy 12.1539 -5.207)
			)
			(stroke
				(width 0)
				(type default)
			)
			(fill no)
			(layer "F.CrtYd")
		)
		(fp_rect
			(start -12.1539 1.6002)
			(end 12.1539 -5.207)
			(stroke
				(width 0)
				(type default)
			)
			(fill no)
			(layer "F.Fab")
		)
		(pad "1" thru_hole circle
			(at 4.99999 0 270)
			(size 1.4732 1.4732)
			(drill 1.0668)
			(layers "*.Cu" "*.Mask")
			(remove_unused_layers no)
			(net "P3V0_BAT")
			(clearance 0.1524)
			(thermal_gap 0.1524)
		)
		(pad "2" thru_hole circle
			(at 0 -3.599942 270)
			(size 1.4732 1.4732)
			(drill 1.0668)
			(layers "*.Cu" "*.Mask")
			(remove_unused_layers no)
			(net "GND")
			(clearance 0.1524)
			(thermal_gap 0.1524)
		)
		(pad "3" thru_hole circle
			(at -4.99999 0 270)
			(size 1.4732 1.4732)
			(drill 1.0668)
			(layers "*.Cu" "*.Mask")
			(remove_unused_layers no)
			(net "P3V0_BAT")
			(clearance 0.1524)
			(thermal_gap 0.1524)
		)
	)
	(footprint ""
		(layer "F.Cu")
		(at 204.793596 -111.906812)
		(property "Reference" "PC225"
			(at 0 0 0)
			(layer "F.SilkS")
			(hide yes)
			(effects
				(font
					(size 1.27 1.27)
				)
			)
		)
		(property "Value" "SCD1U16V2KX-3GP"
			(at 1.1811 -2.7051 0)
			(unlocked yes)
			(layer "F.Fab")
			(hide yes)
			(effects
				(font
					(size 1.016 1.016)
					(thickness 0.1524)
				)
			)
		)
		(property "Device Type" "C402H22"
			(at 1.1811 -4.2291 0)
			(unlocked yes)
			(layer "F.Fab")
			(hide yes)
			(effects
				(font
					(size 1.016 1.016)
					(thickness 0.1524)
				)
			)
		)
		(duplicate_pad_numbers_are_jumpers no)
		(fp_rect
			(start -0.4318 0.9525)
			(end 0.4318 -0.9525)
			(stroke
				(width 0)
				(type default)
			)
			(fill no)
			(layer "F.CrtYd")
		)
		(fp_rect
			(start -0.4318 0.9525)
			(end 0.4318 -0.9525)
			(stroke
				(width 0)
				(type default)
			)
			(fill no)
			(layer "F.Fab")
		)
		(pad "1" smd custom
			(at 0 -0.4445)
			(size 0.1524 0.1524)
			(layers "F.Cu" "F.Mask" "F.Paste")
			(net "P1V5_E_VIN")
			(options
				(clearance outline)
				(anchor circle)
			)
			(primitives
				(gr_poly
					(pts
						(arc
							(start 0.3048 -0.2032)
							(mid 0.275042 -0.275042)
							(end 0.2032 -0.3048)
						)
						(arc
							(start -0.2032 -0.3048)
							(mid -0.275042 -0.275042)
							(end -0.3048 -0.2032)
						)
						(arc
							(start -0.3048 0.2032)
							(mid -0.275042 0.275042)
							(end -0.2032 0.3048)
						)
						(arc
							(start 0.2032 0.3048)
							(mid 0.275042 0.275042)
							(end 0.3048 0.2032)
						)
					)
					(width 0)
					(fill yes)
				)
			)
		)
		(pad "2" smd custom
			(at 0 0.4445)
			(size 0.1524 0.1524)
			(layers "F.Cu" "F.Mask" "F.Paste")
			(net "GND")
			(options
				(clearance outline)
				(anchor circle)
			)
			(primitives
				(gr_poly
					(pts
						(arc
							(start 0.3048 -0.2032)
							(mid 0.275042 -0.275042)
							(end 0.2032 -0.3048)
						)
						(arc
							(start -0.2032 -0.3048)
							(mid -0.275042 -0.275042)
							(end -0.3048 -0.2032)
						)
						(arc
							(start -0.3048 0.2032)
							(mid -0.275042 0.275042)
							(end -0.2032 0.3048)
						)
						(arc
							(start 0.2032 0.3048)
							(mid 0.275042 0.275042)
							(end 0.3048 0.2032)
						)
					)
					(width 0)
					(fill yes)
				)
			)
		)
	)
	(footprint ""
		(layer "F.Cu")
		(at 89.662 -18.796 180)
		(property "Reference" "PC219"
			(at 0 0 180)
			(layer "F.SilkS")
			(hide yes)
			(effects
				(font
					(size 1.27 1.27)
				)
			)
		)
		(property "Value" "SCD1U50V3KX-GP"
			(at 0 -2.8194 180)
			(unlocked yes)
			(layer "F.Fab")
			(hide yes)
			(effects
				(font
					(size 1.016 1.016)
					(thickness 0.1524)
				)
			)
		)
		(property "Device Type" "C603H36"
			(at 0 -4.3434 180)
			(unlocked yes)
			(layer "F.Fab")
			(hide yes)
			(effects
				(font
					(size 1.016 1.016)
					(thickness 0.1524)
				)
			)
		)
		(duplicate_pad_numbers_are_jumpers no)
		(fp_line
			(start 0.508 0)
			(end -0.508 0)
			(stroke
				(width 0.2032)
				(type default)
			)
			(layer "F.SilkS")
		)
		(fp_rect
			(start -0.5842 1.3335)
			(end 0.5842 -1.3335)
			(stroke
				(width 0)
				(type default)
			)
			(fill no)
			(layer "F.CrtYd")
		)
		(fp_rect
			(start -0.5842 1.3335)
			(end 0.5842 -1.3335)
			(stroke
				(width 0)
				(type default)
			)
			(fill no)
			(layer "F.Fab")
		)
		(pad "1" smd custom
			(at 0 -0.762 180)
			(size 0.2159 0.2159)
			(layers "F.Cu" "F.Mask" "F.Paste")
			(net "VT235_VDES_RC")
			(options
				(clearance outline)
				(anchor circle)
			)
			(primitives
				(gr_poly
					(pts
						(arc
							(start -0.3302 -0.4318)
							(mid -0.402042 -0.402042)
							(end -0.4318 -0.3302)
						)
						(arc
							(start -0.4318 0.3302)
							(mid -0.402042 0.402042)
							(end -0.3302 0.4318)
						)
						(arc
							(start 0.3302 0.4318)
							(mid 0.402042 0.402042)
							(end 0.4318 0.3302)
						)
						(arc
							(start 0.4318 -0.3302)
							(mid 0.402042 -0.402042)
							(end 0.3302 -0.4318)
						)
					)
					(width 0)
					(fill yes)
				)
			)
		)
		(pad "2" smd custom
			(at 0 0.762 180)
			(size 0.2159 0.2159)
			(layers "F.Cu" "F.Mask" "F.Paste")
			(net "VT235_VDES_RCC")
			(options
				(clearance outline)
				(anchor circle)
			)
			(primitives
				(gr_poly
					(pts
						(arc
							(start -0.3302 -0.4318)
							(mid -0.402042 -0.402042)
							(end -0.4318 -0.3302)
						)
						(arc
							(start -0.4318 0.3302)
							(mid -0.402042 0.402042)
							(end -0.3302 0.4318)
						)
						(arc
							(start 0.3302 0.4318)
							(mid 0.402042 0.402042)
							(end 0.4318 0.3302)
						)
						(arc
							(start 0.4318 -0.3302)
							(mid 0.402042 -0.402042)
							(end 0.3302 -0.4318)
						)
					)
					(width 0)
					(fill yes)
				)
			)
		)
	)
	(footprint ""
		(layer "F.Cu")
		(at 276.987 -21.59 180)
		(property "Reference" "U22"
			(at 0 0 180)
			(layer "F.SilkS")
			(hide yes)
			(effects
				(font
					(size 1.27 1.27)
				)
			)
		)
		(property "Value" "AZC099-04S-1-GP"
			(at -0.0254 -11.9634 180)
			(unlocked yes)
			(layer "F.Fab")
			(hide yes)
			(effects
				(font
					(size 1.016 1.016)
					(thickness 0.1524)
				)
			)
		)
		(property "Device Type" "SOT-6H58"
			(at -0.0254 -13.5636 180)
			(unlocked yes)
			(layer "F.Fab")
			(hide yes)
			(effects
				(font
					(size 1.016 1.016)
					(thickness 0.1524)
				)
			)
		)
		(duplicate_pad_numbers_are_jumpers no)
		(fp_line
			(start 1.7145 0.5842)
			(end 1.7145 -0.5842)
			(stroke
				(width 0.1524)
				(type default)
			)
			(layer "F.SilkS")
		)
		(fp_line
			(start 1.7145 -0.5842)
			(end -1.9685 -0.5842)
			(stroke
				(width 0.1524)
				(type default)
			)
			(layer "F.SilkS")
		)
		(fp_line
			(start -1.5621 0)
			(end -1.9685 0.4064)
			(stroke
				(width 0.1524)
				(type default)
			)
			(layer "F.SilkS")
		)
		(fp_line
			(start -1.9685 0.5842)
			(end 1.7145 0.5842)
			(stroke
				(width 0.1524)
				(type default)
			)
			(layer "F.SilkS")
		)
		(fp_line
			(start -1.9685 0.5842)
			(end -1.9685 2.3622)
			(stroke
				(width 0.508)
				(type default)
			)
			(layer "F.SilkS")
		)
		(fp_line
			(start -1.9685 -0.4064)
			(end -1.5621 0)
			(stroke
				(width 0.1524)
				(type default)
			)
			(layer "F.SilkS")
		)
		(fp_line
			(start -1.9685 -0.5842)
			(end -1.9685 0.5842)
			(stroke
				(width 0.1524)
				(type default)
			)
			(layer "F.SilkS")
		)
		(fp_poly
			(pts
				(xy -1.27 -0.635) (xy 1.27 -0.635) (xy 1.27 0.635) (xy -1.27 0.635)
			)
			(stroke
				(width 0)
				(type default)
			)
			(fill yes)
			(layer "F.SilkS")
		)
		(fp_rect
			(start -1.9685 2.3622)
			(end 1.9685 -2.3622)
			(stroke
				(width 0)
				(type default)
			)
			(fill no)
			(layer "F.CrtYd")
		)
		(fp_poly
			(pts
				(xy -1.9685 -2.3622) (xy 1.9685 -2.3622) (xy 1.9685 2.3622) (xy -1.9685 2.3622)
			)
			(stroke
				(width 0)
				(type default)
			)
			(fill no)
			(layer "F.Fab")
		)
		(pad "1" smd rect
			(at -0.9525 1.3462 180)
			(size 0.5842 1.016)
			(layers "F.Cu" "F.Mask" "F.Paste")
			(net "USB_P1_F_DP1")
		)
		(pad "2" smd rect
			(at 0 1.3462 180)
			(size 0.5842 1.016)
			(layers "F.Cu" "F.Mask" "F.Paste")
			(net "GND")
		)
		(pad "3" smd rect
			(at 0.9525 1.3462 180)
			(size 0.5842 1.016)
			(layers "F.Cu" "F.Mask" "F.Paste")
			(net "Net_404")
		)
		(pad "4" smd rect
			(at 0.9525 -1.3462 180)
			(size 0.5842 1.016)
			(layers "F.Cu" "F.Mask" "F.Paste")
			(net "Net_405")
		)
		(pad "5" smd rect
			(at 0 -1.3462 180)
			(size 0.5842 1.016)
			(layers "F.Cu" "F.Mask" "F.Paste")
			(net "P5V_USB")
		)
		(pad "6" smd rect
			(at -0.9525 -1.3462 180)
			(size 0.5842 1.016)
			(layers "F.Cu" "F.Mask" "F.Paste")
			(net "USB_P1_F_DN1")
		)
	)
	(footprint ""
		(layer "F.Cu")
		(at 192.151 -225.806 -90)
		(property "Reference" "U175"
			(at 0 0 270)
			(layer "F.SilkS")
			(hide yes)
			(effects
				(font
					(size 1.27 1.27)
				)
			)
		)
		(property "Value" "TSLVC14APW-2-GP"
			(at 0.1016 -7.62 270)
			(unlocked yes)
			(layer "F.Fab")
			(hide yes)
			(effects
				(font
					(size 1.016 1.016)
					(thickness 0.1524)
				)
			)
		)
		(property "Device Type" "TSOIC14H44"
			(at 0.1016 -10.16 270)
			(unlocked yes)
			(layer "F.Fab")
			(hide yes)
			(effects
				(font
					(size 1.016 1.016)
					(thickness 0.1524)
				)
			)
		)
		(duplicate_pad_numbers_are_jumpers no)
		(fp_line
			(start -3.048 4.191)
			(end -3.048 1.397)
			(stroke
				(width 0.508)
				(type default)
			)
			(layer "F.SilkS")
		)
		(fp_line
			(start 2.159 1.778)
			(end 2.159 1.7526)
			(stroke
				(width 0.2032)
				(type default)
			)
			(layer "F.SilkS")
		)
		(fp_line
			(start 2.159 1.7526)
			(end -3.0734 1.7526)
			(stroke
				(width 0.2032)
				(type default)
			)
			(layer "F.SilkS")
		)
		(fp_line
			(start -2.032 0)
			(end -3.048 1.016)
			(stroke
				(width 0.2032)
				(type default)
			)
			(layer "F.SilkS")
		)
		(fp_line
			(start -2.032 0)
			(end -3.048 -1.016)
			(stroke
				(width 0.2032)
				(type default)
			)
			(layer "F.SilkS")
		)
		(fp_line
			(start -3.048 -1.778)
			(end -3.048 4.191)
			(stroke
				(width 0.2032)
				(type default)
			)
			(layer "F.SilkS")
		)
		(fp_line
			(start -3.048 -1.778)
			(end 2.159 -1.778)
			(stroke
				(width 0.2032)
				(type default)
			)
			(layer "F.SilkS")
		)
		(fp_line
			(start 2.159 -1.778)
			(end 2.159 1.778)
			(stroke
				(width 0.2032)
				(type default)
			)
			(layer "F.SilkS")
		)
		(fp_poly
			(pts
				(xy -2.2606 -1.8542) (xy 2.2606 -1.8542) (xy 2.2606 1.8542) (xy -2.2606 1.8542)
			)
			(stroke
				(width 0)
				(type default)
			)
			(fill yes)
			(layer "F.SilkS")
		)
		(fp_poly
			(pts
				(xy -3.048 -4.0894) (xy 3.048 -4.0894) (xy 3.048 4.0894) (xy -3.048 4.0894)
			)
			(stroke
				(width 0)
				(type default)
			)
			(fill no)
			(layer "F.CrtYd")
		)
		(fp_poly
			(pts
				(xy -3.048 -4.0894) (xy 3.048 -4.0894) (xy 3.048 4.0894) (xy -3.048 4.0894)
			)
			(stroke
				(width 0)
				(type default)
			)
			(fill no)
			(layer "F.Fab")
		)
		(pad "1" smd rect
			(at -1.94945 2.8194 270)
			(size 0.3556 1.524)
			(layers "F.Cu" "F.Mask" "F.Paste")
			(net "FP_PWRBTN_RC_N")
		)
		(pad "2" smd rect
			(at -1.30048 2.8194 270)
			(size 0.3556 1.524)
			(layers "F.Cu" "F.Mask" "F.Paste")
			(net "FP_PWRBTN")
		)
		(pad "3" smd rect
			(at -0.65024 2.8194 270)
			(size 0.3556 1.524)
			(layers "F.Cu" "F.Mask" "F.Paste")
			(net "FP_PWRBTN_R")
		)
		(pad "4" smd rect
			(at 0 2.8194 270)
			(size 0.3556 1.524)
			(layers "F.Cu" "F.Mask" "F.Paste")
			(net "PWRBTN_FP_N")
		)
		(pad "5" smd rect
			(at 0.65024 2.8194 270)
			(size 0.3556 1.524)
			(layers "F.Cu" "F.Mask" "F.Paste")
			(net "FP_RESET_RC_N")
		)
		(pad "6" smd rect
			(at 1.30048 2.8194 270)
			(size 0.3556 1.524)
			(layers "F.Cu" "F.Mask" "F.Paste")
			(net "FP_RETBTN")
		)
		(pad "7" smd rect
			(at 1.94945 2.8194 270)
			(size 0.3556 1.524)
			(layers "F.Cu" "F.Mask" "F.Paste")
			(net "GND")
		)
		(pad "8" smd rect
			(at 1.94945 -2.8194 270)
			(size 0.3556 1.524)
			(layers "F.Cu" "F.Mask" "F.Paste")
			(net "RSTBTN_FP_N")
		)
		(pad "9" smd rect
			(at 1.30048 -2.8194 270)
			(size 0.3556 1.524)
			(layers "F.Cu" "F.Mask" "F.Paste")
			(net "FP_RETBTN_R")
		)
		(pad "10" smd rect
			(at 0.65024 -2.8194 270)
			(size 0.3556 1.524)
			(layers "F.Cu" "F.Mask" "F.Paste")
			(net "Net_401")
		)
		(pad "11" smd rect
			(at 0 -2.8194 270)
			(size 0.3556 1.524)
			(layers "F.Cu" "F.Mask" "F.Paste")
			(net "Net_400")
		)
		(pad "12" smd rect
			(at -0.65024 -2.8194 270)
			(size 0.3556 1.524)
			(layers "F.Cu" "F.Mask" "F.Paste")
			(net "Net_399")
		)
		(pad "13" smd rect
			(at -1.30048 -2.8194 270)
			(size 0.3556 1.524)
			(layers "F.Cu" "F.Mask" "F.Paste")
			(net "Net_398")
		)
		(pad "14" smd rect
			(at -1.94945 -2.8194 270)
			(size 0.3556 1.524)
			(layers "F.Cu" "F.Mask" "F.Paste")
			(net "P3V3_STBY")
		)
	)
)
